# S9S_MB_2U (Grand Teton) — schematic netlist excerpt (pin names and nets, part order shuffled) for the footprints in the layout excerpt that follows; sources: Cadence DE-HDL packaged netlist, KiCad conversion of 03242023_DA0F0TMBIJ0_F0T_Motherboard_J_brd_V01_OCP.brd

C590  Q_CAP  22UF 4V 20% X6S  pkg C0402  page 74 : A = PVNN_MAIN_CPU0 ; B = GND
C1614  Q_CAP  0.1UF 25V 10% X7R  pkg 0402  page 191 : A = P3V3_AUX ; B = GND

(kicad_pcb
	(version 20260206)
	(generator "pcbnew")
	(generator_version "10.0")
	(general
		(thickness 1.6)
		(legacy_teardrops no)
	)
	(paper "A4")
	(title_block
		(title "03242023_DA0F0TMBIJ0_F0T_Motherboard_J_brd_V01_OCP.brd")
		(comment 1 "Grand Teton / footprints 809-810 of 6105")
	)
	(layers
		(0 "F.Cu" signal "TOP")
		(4 "In1.Cu" signal "GND")
		(6 "In2.Cu" signal "IN1")
		(8 "In3.Cu" signal "GND1")
		(10 "In4.Cu" signal "IN2")
		(12 "In5.Cu" signal "GND2")
		(14 "In6.Cu" signal "IN3")
		(16 "In7.Cu" signal "GND3")
		(18 "In8.Cu" signal "VCC")
		(20 "In9.Cu" signal "VCC1")
		(22 "In10.Cu" signal "GND4")
		(24 "In11.Cu" signal "IN4")
		(26 "In12.Cu" signal "GND5")
		(28 "In13.Cu" signal "IN5")
		(30 "In14.Cu" signal "GND6")
		(32 "In15.Cu" signal "IN6")
		(34 "In16.Cu" signal "GND7")
		(2 "B.Cu" signal "BOTTOM")
		(9 "F.Adhes" user "F.Adhesive")
		(11 "B.Adhes" user "B.Adhesive")
		(13 "F.Paste" user "Package Geometry/Pastemask Top")
		(15 "B.Paste" user "Package Geometry/Pastemask Bottom")
		(5 "F.SilkS" user "Ref Des/Silkscreen Top")
		(7 "B.SilkS" user "Ref Des/Silkscreen Bottom")
		(1 "F.Mask" user "Board Geometry/Soldermask Top")
		(3 "B.Mask" user "Board Geometry/Soldermask Bottom")
		(17 "Dwgs.User" user "User.Drawings")
		(19 "Cmts.User" user "User.Comments")
		(21 "Eco1.User" user "User.Eco1")
		(23 "Eco2.User" user "User.Eco2")
		(25 "Edge.Cuts" user "Board Geometry/Outline")
		(27 "Margin" user)
		(31 "F.CrtYd" user "Package Geometry/Place Bound Top")
		(29 "B.CrtYd" user "Package Geometry/Place Bound Bottom")
		(35 "F.Fab" user "Ref Des/Assembly Top")
		(33 "B.Fab" user "Ref Des/Assembly Bottom")
	)
	(footprint ""
		(layer "F.Cu")
		(at 353.242626 -238.160052 90)
		(property "Reference" "C590"
			(at 0 0 90)
			(layer "F.SilkS")
			(hide yes)
			(effects
				(font
					(size 1.27 1.27)
				)
			)
		)
		(property "Value" ""
			(at 0 0 90)
			(layer "F.Fab")
			(effects
				(font
					(size 1.27 1.27)
				)
			)
		)
		(duplicate_pad_numbers_are_jumpers no)
		(fp_line
			(start 0.7874 -0.4064)
			(end 0.7874 0.4064)
			(stroke
				(width 0.1524)
				(type default)
			)
			(layer "F.SilkS")
		)
		(fp_line
			(start -0.7874 -0.4064)
			(end 0.7874 -0.4064)
			(stroke
				(width 0.1524)
				(type default)
			)
			(layer "F.SilkS")
		)
		(fp_line
			(start 0.7874 0.4064)
			(end -0.7874 0.4064)
			(stroke
				(width 0.1524)
				(type default)
			)
			(layer "F.SilkS")
		)
		(fp_line
			(start -0.7874 0.4064)
			(end -0.7874 -0.4064)
			(stroke
				(width 0.1524)
				(type default)
			)
			(layer "F.SilkS")
		)
		(fp_line
			(start -0.12065 -0.305054)
			(end -0.12065 -0.2794)
			(stroke
				(width 0.1)
				(type default)
			)
			(layer "F.Fab")
		)
		(fp_line
			(start -0.67945 -0.305054)
			(end -0.12065 -0.305054)
			(stroke
				(width 0.1)
				(type default)
			)
			(layer "F.Fab")
		)
		(fp_line
			(start 0.67945 -0.3048)
			(end 0.67945 0.3048)
			(stroke
				(width 0.1)
				(type default)
			)
			(layer "F.Fab")
		)
		(fp_line
			(start 0.12065 -0.3048)
			(end 0.67945 -0.3048)
			(stroke
				(width 0.1)
				(type default)
			)
			(layer "F.Fab")
		)
		(fp_line
			(start 0.12065 -0.2794)
			(end 0.12065 -0.3048)
			(stroke
				(width 0.1)
				(type default)
			)
			(layer "F.Fab")
		)
		(fp_line
			(start -0.12065 -0.2794)
			(end 0.12065 -0.2794)
			(stroke
				(width 0.1)
				(type default)
			)
			(layer "F.Fab")
		)
		(fp_line
			(start 0.120396 0.2794)
			(end -0.12065 0.2794)
			(stroke
				(width 0.1)
				(type default)
			)
			(layer "F.Fab")
		)
		(fp_line
			(start -0.12065 0.2794)
			(end -0.12065 0.3048)
			(stroke
				(width 0.1)
				(type default)
			)
			(layer "F.Fab")
		)
		(fp_line
			(start 0.67945 0.3048)
			(end 0.120396 0.3048)
			(stroke
				(width 0.1)
				(type default)
			)
			(layer "F.Fab")
		)
		(fp_line
			(start 0.120396 0.3048)
			(end 0.120396 0.2794)
			(stroke
				(width 0.1)
				(type default)
			)
			(layer "F.Fab")
		)
		(fp_line
			(start -0.12065 0.3048)
			(end -0.67945 0.3048)
			(stroke
				(width 0.1)
				(type default)
			)
			(layer "F.Fab")
		)
		(fp_line
			(start -0.67945 0.3048)
			(end -0.67945 -0.305054)
			(stroke
				(width 0.1)
				(type default)
			)
			(layer "F.Fab")
		)
		(pad "1" smd circle
			(at -0.40005 0 90)
			(size 0 0)
			(layers "F.Cu" "F.Mask" "F.Paste")
			(net "PVNN_MAIN_CPU0")
		)
		(pad "2" smd circle
			(at 0.40005 0 90)
			(size 0 0)
			(layers "F.Cu" "F.Mask" "F.Paste")
			(net "GND")
		)
	)
	(footprint ""
		(layer "F.Cu")
		(at 146.541236 -66.708528)
		(property "Reference" "C1614"
			(at 0 0 0)
			(layer "F.SilkS")
			(hide yes)
			(effects
				(font
					(size 1.27 1.27)
				)
			)
		)
		(property "Value" ""
			(at 0 0 0)
			(layer "F.Fab")
			(effects
				(font
					(size 1.27 1.27)
				)
			)
		)
		(duplicate_pad_numbers_are_jumpers no)
		(fp_line
			(start -0.7874 -0.4064)
			(end 0.7874 -0.4064)
			(stroke
				(width 0.1524)
				(type default)
			)
			(layer "F.SilkS")
		)
		(fp_line
			(start -0.7874 0.4064)
			(end -0.7874 -0.4064)
			(stroke
				(width 0.1524)
				(type default)
			)
			(layer "F.SilkS")
		)
		(fp_line
			(start 0.7874 -0.4064)
			(end 0.7874 0.4064)
			(stroke
				(width 0.1524)
				(type default)
			)
			(layer "F.SilkS")
		)
		(fp_line
			(start 0.7874 0.4064)
			(end -0.7874 0.4064)
			(stroke
				(width 0.1524)
				(type default)
			)
			(layer "F.SilkS")
		)
		(fp_line
			(start -0.67945 -0.305054)
			(end -0.12065 -0.305054)
			(stroke
				(width 0.1)
				(type default)
			)
			(layer "F.Fab")
		)
		(fp_line
			(start -0.67945 0.3048)
			(end -0.67945 -0.305054)
			(stroke
				(width 0.1)
				(type default)
			)
			(layer "F.Fab")
		)
		(fp_line
			(start -0.12065 -0.305054)
			(end -0.12065 -0.2794)
			(stroke
				(width 0.1)
				(type default)
			)
			(layer "F.Fab")
		)
		(fp_line
			(start -0.12065 -0.2794)
			(end 0.12065 -0.2794)
			(stroke
				(width 0.1)
				(type default)
			)
			(layer "F.Fab")
		)
		(fp_line
			(start -0.12065 0.2794)
			(end -0.12065 0.3048)
			(stroke
				(width 0.1)
				(type default)
			)
			(layer "F.Fab")
		)
		(fp_line
			(start -0.12065 0.3048)
			(end -0.67945 0.3048)
			(stroke
				(width 0.1)
				(type default)
			)
			(layer "F.Fab")
		)
		(fp_line
			(start 0.120396 0.2794)
			(end -0.12065 0.2794)
			(stroke
				(width 0.1)
				(type default)
			)
			(layer "F.Fab")
		)
		(fp_line
			(start 0.120396 0.3048)
			(end 0.120396 0.2794)
			(stroke
				(width 0.1)
				(type default)
			)
			(layer "F.Fab")
		)
		(fp_line
			(start 0.12065 -0.3048)
			(end 0.67945 -0.3048)
			(stroke
				(width 0.1)
				(type default)
			)
			(layer "F.Fab")
		)
		(fp_line
			(start 0.12065 -0.2794)
			(end 0.12065 -0.3048)
			(stroke
				(width 0.1)
				(type default)
			)
			(layer "F.Fab")
		)
		(fp_line
			(start 0.67945 -0.3048)
			(end 0.67945 0.3048)
			(stroke
				(width 0.1)
				(type default)
			)
			(layer "F.Fab")
		)
		(fp_line
			(start 0.67945 0.3048)
			(end 0.120396 0.3048)
			(stroke
				(width 0.1)
				(type default)
			)
			(layer "F.Fab")
		)
		(pad "1" smd circle
			(at -0.40005 0)
			(size 0 0)
			(layers "F.Cu" "F.Mask" "F.Paste")
			(net "P3V3_AUX")
		)
		(pad "2" smd circle
			(at 0.40005 0)
			(size 0 0)
			(layers "F.Cu" "F.Mask" "F.Paste")
			(net "GND")
		)
	)
)
